# S9S_MB_2U (Grand Teton) — schematic netlist excerpt (pin names and nets, part order shuffled) for the footprints in the layout excerpt that follows; sources: Cadence DE-HDL packaged netlist, KiCad conversion of 03242023_DA0F0TMBIJ0_F0T_Motherboard_J_brd_V01_OCP.brd

Q133  MOSFET_NCH_DUAL  PJT138K IC  pkg SOT363XD  page 146
  S1  = GND
  G1  = PRSNT_CABLE_GPU_A2_N
  D2  = PRSNT_CABLE_GPU_A2_ISO_N
  S2  = GND
  G2  = PRSNT_CABLE_GPU_A2
  D1  = PRSNT_CABLE_GPU_A2

R4064  Q_RES  0 5% CHIP  pkg 0402LF  page 192 : A = E1S_0_EN ; B = P12V_E1S_EN_0_R

(kicad_pcb
	(version 20260206)
	(generator "pcbnew")
	(generator_version "10.0")
	(general
		(thickness 1.6)
		(legacy_teardrops no)
	)
	(paper "A4")
	(title_block
		(title "03242023_DA0F0TMBIJ0_F0T_Motherboard_J_brd_V01_OCP.brd")
		(comment 1 "Grand Teton / footprints 3297-3298 of 6105")
	)
	(layers
		(0 "F.Cu" signal "TOP")
		(4 "In1.Cu" signal "GND")
		(6 "In2.Cu" signal "IN1")
		(8 "In3.Cu" signal "GND1")
		(10 "In4.Cu" signal "IN2")
		(12 "In5.Cu" signal "GND2")
		(14 "In6.Cu" signal "IN3")
		(16 "In7.Cu" signal "GND3")
		(18 "In8.Cu" signal "VCC")
		(20 "In9.Cu" signal "VCC1")
		(22 "In10.Cu" signal "GND4")
		(24 "In11.Cu" signal "IN4")
		(26 "In12.Cu" signal "GND5")
		(28 "In13.Cu" signal "IN5")
		(30 "In14.Cu" signal "GND6")
		(32 "In15.Cu" signal "IN6")
		(34 "In16.Cu" signal "GND7")
		(2 "B.Cu" signal "BOTTOM")
		(9 "F.Adhes" user "F.Adhesive")
		(11 "B.Adhes" user "B.Adhesive")
		(13 "F.Paste" user "Package Geometry/Pastemask Top")
		(15 "B.Paste" user "Package Geometry/Pastemask Bottom")
		(5 "F.SilkS" user "Ref Des/Silkscreen Top")
		(7 "B.SilkS" user "Ref Des/Silkscreen Bottom")
		(1 "F.Mask" user "Board Geometry/Soldermask Top")
		(3 "B.Mask" user "Board Geometry/Soldermask Bottom")
		(17 "Dwgs.User" user "User.Drawings")
		(19 "Cmts.User" user "User.Comments")
		(21 "Eco1.User" user "User.Eco1")
		(23 "Eco2.User" user "User.Eco2")
		(25 "Edge.Cuts" user "Board Geometry/Outline")
		(27 "Margin" user)
		(31 "F.CrtYd" user "Package Geometry/Place Bound Top")
		(29 "B.CrtYd" user "Package Geometry/Place Bound Bottom")
		(35 "F.Fab" user "Ref Des/Assembly Top")
		(33 "B.Fab" user "Ref Des/Assembly Bottom")
	)
	(footprint ""
		(layer "F.Cu")
		(at 293.80688 -46.954948 90)
		(property "Reference" "R4064"
			(at 0 0 90)
			(layer "F.SilkS")
			(hide yes)
			(effects
				(font
					(size 1.27 1.27)
				)
			)
		)
		(property "Value" ""
			(at 0 0 90)
			(layer "F.Fab")
			(effects
				(font
					(size 1.27 1.27)
				)
			)
		)
		(duplicate_pad_numbers_are_jumpers no)
		(fp_line
			(start 0.7874 -0.4064)
			(end 0.7874 0.4064)
			(stroke
				(width 0.1524)
				(type default)
			)
			(layer "F.SilkS")
		)
		(fp_line
			(start -0.7874 -0.4064)
			(end 0.7874 -0.4064)
			(stroke
				(width 0.1524)
				(type default)
			)
			(layer "F.SilkS")
		)
		(fp_line
			(start 0.7874 0.4064)
			(end -0.7874 0.4064)
			(stroke
				(width 0.1524)
				(type default)
			)
			(layer "F.SilkS")
		)
		(fp_line
			(start -0.7874 0.4064)
			(end -0.7874 -0.4064)
			(stroke
				(width 0.1524)
				(type default)
			)
			(layer "F.SilkS")
		)
		(fp_line
			(start -0.12065 -0.305054)
			(end -0.12065 -0.2794)
			(stroke
				(width 0.1)
				(type default)
			)
			(layer "F.Fab")
		)
		(fp_line
			(start -0.67945 -0.305054)
			(end -0.12065 -0.305054)
			(stroke
				(width 0.1)
				(type default)
			)
			(layer "F.Fab")
		)
		(fp_line
			(start 0.67945 -0.3048)
			(end 0.67945 0.3048)
			(stroke
				(width 0.1)
				(type default)
			)
			(layer "F.Fab")
		)
		(fp_line
			(start 0.12065 -0.3048)
			(end 0.67945 -0.3048)
			(stroke
				(width 0.1)
				(type default)
			)
			(layer "F.Fab")
		)
		(fp_line
			(start 0.12065 -0.2794)
			(end 0.12065 -0.3048)
			(stroke
				(width 0.1)
				(type default)
			)
			(layer "F.Fab")
		)
		(fp_line
			(start -0.12065 -0.2794)
			(end 0.12065 -0.2794)
			(stroke
				(width 0.1)
				(type default)
			)
			(layer "F.Fab")
		)
		(fp_line
			(start 0.120396 0.2794)
			(end -0.12065 0.2794)
			(stroke
				(width 0.1)
				(type default)
			)
			(layer "F.Fab")
		)
		(fp_line
			(start -0.12065 0.2794)
			(end -0.12065 0.3048)
			(stroke
				(width 0.1)
				(type default)
			)
			(layer "F.Fab")
		)
		(fp_line
			(start 0.67945 0.3048)
			(end 0.120396 0.3048)
			(stroke
				(width 0.1)
				(type default)
			)
			(layer "F.Fab")
		)
		(fp_line
			(start 0.120396 0.3048)
			(end 0.120396 0.2794)
			(stroke
				(width 0.1)
				(type default)
			)
			(layer "F.Fab")
		)
		(fp_line
			(start -0.12065 0.3048)
			(end -0.67945 0.3048)
			(stroke
				(width 0.1)
				(type default)
			)
			(layer "F.Fab")
		)
		(fp_line
			(start -0.67945 0.3048)
			(end -0.67945 -0.305054)
			(stroke
				(width 0.1)
				(type default)
			)
			(layer "F.Fab")
		)
		(pad "1" smd circle
			(at -0.40005 0 90)
			(size 0 0)
			(layers "F.Cu" "F.Mask" "F.Paste")
			(net "E1S_0_EN")
		)
		(pad "2" smd circle
			(at 0.40005 0 90)
			(size 0 0)
			(layers "F.Cu" "F.Mask" "F.Paste")
			(net "P12V_E1S_EN_0_R")
		)
	)
	(footprint ""
		(layer "F.Cu")
		(at 305.92014 -435.6481 90)
		(property "Reference" "Q133"
			(at -7.36346 -4.155948 90)
			(unlocked yes)
			(layer "F.SilkS")
			(effects
				(font
					(size 0.7874 0.5842)
					(thickness 0.1524)
				)
				(justify left)
			)
		)
		(property "Value" ""
			(at 0 0 90)
			(layer "F.Fab")
			(effects
				(font
					(size 1.27 1.27)
				)
			)
		)
		(duplicate_pad_numbers_are_jumpers no)
		(fp_line
			(start 1.332738 -1.100074)
			(end 1.332738 1.100074)
			(stroke
				(width 0.1524)
				(type default)
			)
			(layer "F.SilkS")
		)
		(fp_line
			(start 0.4826 -1.100074)
			(end 1.332738 -1.100074)
			(stroke
				(width 0.1524)
				(type default)
			)
			(layer "F.SilkS")
		)
		(fp_line
			(start -0.4826 -1.100074)
			(end 0 -0.541274)
			(stroke
				(width 0.1524)
				(type default)
			)
			(layer "F.SilkS")
		)
		(fp_line
			(start -1.332738 -1.100074)
			(end -0.4826 -1.100074)
			(stroke
				(width 0.1524)
				(type default)
			)
			(layer "F.SilkS")
		)
		(fp_line
			(start 0 -0.541274)
			(end 0.4826 -1.100074)
			(stroke
				(width 0.1524)
				(type default)
			)
			(layer "F.SilkS")
		)
		(fp_line
			(start 1.332738 1.100074)
			(end -1.332738 1.100074)
			(stroke
				(width 0.1524)
				(type default)
			)
			(layer "F.SilkS")
		)
		(fp_line
			(start -1.332738 1.100074)
			(end -1.332738 -1.100074)
			(stroke
				(width 0.1524)
				(type default)
			)
			(layer "F.SilkS")
		)
		(fp_poly
			(pts
				(xy -2.29362 -1.321054) (xy -1.591564 -0.970026) (xy -2.29362 -0.618998)
			)
			(stroke
				(width 0)
				(type default)
			)
			(fill yes)
			(layer "F.SilkS")
		)
		(fp_line
			(start 0.674878 -1.100074)
			(end 0.674878 1.100074)
			(stroke
				(width 0.1)
				(type default)
			)
			(layer "F.Fab")
		)
		(fp_line
			(start -0.674878 -1.100074)
			(end 0.674878 -1.100074)
			(stroke
				(width 0.1)
				(type default)
			)
			(layer "F.Fab")
		)
		(fp_line
			(start 0.674878 1.100074)
			(end -0.674878 1.100074)
			(stroke
				(width 0.1)
				(type default)
			)
			(layer "F.Fab")
		)
		(fp_line
			(start -0.674878 1.100074)
			(end -0.674878 -1.100074)
			(stroke
				(width 0.1)
				(type default)
			)
			(layer "F.Fab")
		)
		(fp_poly
			(pts
				(xy -2.2352 -0.298958) (xy -2.2352 -1.001014) (xy -1.533144 -0.649986)
			)
			(stroke
				(width 0)
				(type default)
			)
			(fill yes)
			(layer "F.Fab")
		)
		(pad "1" smd rect
			(at -0.94996 -0.649986 180)
			(size 0.4318 0.508)
			(layers "F.Cu" "F.Mask" "F.Paste")
			(net "GND")
		)
		(pad "2" smd rect
			(at -0.94996 0 180)
			(size 0.4318 0.508)
			(layers "F.Cu" "F.Mask" "F.Paste")
			(net "PRSNT_CABLE_GPU_A2_N")
		)
		(pad "3" smd rect
			(at -0.94996 0.649986 180)
			(size 0.4318 0.508)
			(layers "F.Cu" "F.Mask" "F.Paste")
			(net "PRSNT_CABLE_GPU_A2_ISO_N")
		)
		(pad "4" smd rect
			(at 0.94996 0.649986 180)
			(size 0.4318 0.508)
			(layers "F.Cu" "F.Mask" "F.Paste")
			(net "GND")
		)
		(pad "5" smd rect
			(at 0.94996 0 180)
			(size 0.4318 0.508)
			(layers "F.Cu" "F.Mask" "F.Paste")
			(net "PRSNT_CABLE_GPU_A2")
		)
		(pad "6" smd rect
			(at 0.94996 -0.649986 180)
			(size 0.4318 0.508)
			(layers "F.Cu" "F.Mask" "F.Paste")
			(net "PRSNT_CABLE_GPU_A2")
		)
	)
)
